# T6G (Grand Teton) — schematic netlist excerpt (pin names and nets, part order shuffled) for the footprints in the layout excerpt that follows; sources: Cadence DE-HDL packaged netlist, KiCad conversion of 04192023_DAF0TMB3IC0_F0TG_MB_C_brd_V02_OCP.brd

PR4011  Q_RES  10K 1% CHIP  pkg 0402LF  page 152 : A = P12V_SCM_OV_FB ; B = GND

(kicad_pcb
	(version 20260206)
	(generator "pcbnew")
	(generator_version "10.0")
	(general
		(thickness 1.6)
		(legacy_teardrops no)
	)
	(paper "A4")
	(title_block
		(title "04192023_DAF0TMB3IC0_F0TG_MB_C_brd_V02_OCP.brd")
		(comment 1 "Grand Teton / footprints 2448-2448 of 8354")
	)
	(layers
		(0 "F.Cu" signal "TOP")
		(4 "In1.Cu" signal "GND")
		(6 "In2.Cu" signal "IN1")
		(8 "In3.Cu" signal "GND1")
		(10 "In4.Cu" signal "IN2")
		(12 "In5.Cu" signal "GND2")
		(14 "In6.Cu" signal "IN3")
		(16 "In7.Cu" signal "GND3")
		(18 "In8.Cu" signal "VCC")
		(20 "In9.Cu" signal "VCC1")
		(22 "In10.Cu" signal "GND4")
		(24 "In11.Cu" signal "IN4")
		(26 "In12.Cu" signal "GND5")
		(28 "In13.Cu" signal "IN5")
		(30 "In14.Cu" signal "GND6")
		(32 "In15.Cu" signal "IN6")
		(34 "In16.Cu" signal "GND7")
		(2 "B.Cu" signal "BOTTOM")
		(9 "F.Adhes" user "F.Adhesive")
		(11 "B.Adhes" user "B.Adhesive")
		(13 "F.Paste" user "Package Geometry/Pastemask Top")
		(15 "B.Paste" user "Package Geometry/Pastemask Bottom")
		(5 "F.SilkS" user "Ref Des/Silkscreen Top")
		(7 "B.SilkS" user "Ref Des/Silkscreen Bottom")
		(1 "F.Mask" user "Board Geometry/Soldermask Top")
		(3 "B.Mask" user "Board Geometry/Soldermask Bottom")
		(17 "Dwgs.User" user "User.Drawings")
		(19 "Cmts.User" user "User.Comments")
		(21 "Eco1.User" user "User.Eco1")
		(23 "Eco2.User" user "User.Eco2")
		(25 "Edge.Cuts" user "Board Geometry/Outline")
		(27 "Margin" user)
		(31 "F.CrtYd" user "Package Geometry/Place Bound Top")
		(29 "B.CrtYd" user "Package Geometry/Place Bound Bottom")
		(35 "F.Fab" user "Ref Des/Assembly Top")
		(33 "B.Fab" user "Ref Des/Assembly Bottom")
	)
	(footprint ""
		(layer "F.Cu")
		(at 173.899322 -28.03779 -90)
		(property "Reference" "PR4011"
			(at 0 0 270)
			(layer "F.SilkS")
			(hide yes)
			(effects
				(font
					(size 1.27 1.27)
				)
			)
		)
		(property "Value" ""
			(at 0 0 270)
			(layer "F.Fab")
			(effects
				(font
					(size 1.27 1.27)
				)
			)
		)
		(duplicate_pad_numbers_are_jumpers no)
		(fp_line
			(start -0.7874 0.4064)
			(end -0.7874 -0.4064)
			(stroke
				(width 0.1524)
				(type default)
			)
			(layer "F.SilkS")
		)
		(fp_line
			(start 0.7874 0.4064)
			(end -0.7874 0.4064)
			(stroke
				(width 0.1524)
				(type default)
			)
			(layer "F.SilkS")
		)
		(fp_line
			(start -0.7874 -0.4064)
			(end 0.7874 -0.4064)
			(stroke
				(width 0.1524)
				(type default)
			)
			(layer "F.SilkS")
		)
		(fp_line
			(start 0.7874 -0.4064)
			(end 0.7874 0.4064)
			(stroke
				(width 0.1524)
				(type default)
			)
			(layer "F.SilkS")
		)
		(fp_line
			(start -0.67945 0.3048)
			(end -0.67945 -0.305054)
			(stroke
				(width 0.1)
				(type default)
			)
			(layer "F.Fab")
		)
		(fp_line
			(start -0.12065 0.3048)
			(end -0.67945 0.3048)
			(stroke
				(width 0.1)
				(type default)
			)
			(layer "F.Fab")
		)
		(fp_line
			(start 0.120396 0.3048)
			(end 0.120396 0.2794)
			(stroke
				(width 0.1)
				(type default)
			)
			(layer "F.Fab")
		)
		(fp_line
			(start 0.67945 0.3048)
			(end 0.120396 0.3048)
			(stroke
				(width 0.1)
				(type default)
			)
			(layer "F.Fab")
		)
		(fp_line
			(start -0.12065 0.2794)
			(end -0.12065 0.3048)
			(stroke
				(width 0.1)
				(type default)
			)
			(layer "F.Fab")
		)
		(fp_line
			(start 0.120396 0.2794)
			(end -0.12065 0.2794)
			(stroke
				(width 0.1)
				(type default)
			)
			(layer "F.Fab")
		)
		(fp_line
			(start -0.12065 -0.2794)
			(end 0.12065 -0.2794)
			(stroke
				(width 0.1)
				(type default)
			)
			(layer "F.Fab")
		)
		(fp_line
			(start 0.12065 -0.2794)
			(end 0.12065 -0.3048)
			(stroke
				(width 0.1)
				(type default)
			)
			(layer "F.Fab")
		)
		(fp_line
			(start 0.12065 -0.3048)
			(end 0.67945 -0.3048)
			(stroke
				(width 0.1)
				(type default)
			)
			(layer "F.Fab")
		)
		(fp_line
			(start 0.67945 -0.3048)
			(end 0.67945 0.3048)
			(stroke
				(width 0.1)
				(type default)
			)
			(layer "F.Fab")
		)
		(fp_line
			(start -0.67945 -0.305054)
			(end -0.12065 -0.305054)
			(stroke
				(width 0.1)
				(type default)
			)
			(layer "F.Fab")
		)
		(fp_line
			(start -0.12065 -0.305054)
			(end -0.12065 -0.2794)
			(stroke
				(width 0.1)
				(type default)
			)
			(layer "F.Fab")
		)
		(pad "1" smd circle
			(at -0.40005 0 270)
			(size 0 0)
			(layers "F.Cu" "F.Mask" "F.Paste")
			(net "P12V_SCM_OV_FB")
		)
		(pad "2" smd circle
			(at 0.40005 0 270)
			(size 0 0)
			(layers "F.Cu" "F.Mask" "F.Paste")
			(net "GND")
		)
	)
)
